# S9S_MB_2U (Grand Teton) — schematic netlist excerpt (pin names and nets, part order shuffled) for the footprints in the layout excerpt that follows; sources: Cadence DE-HDL packaged netlist, KiCad conversion of 03242023_DA0F0TMBIJ0_F0T_Motherboard_J_brd_V01_OCP.brd

R2342  Q_RES  10K 1% CHIP  pkg 0402LF  page 204 : A = P3V3_AUX ; B = FM_DEBUG_PORT_PRSNT_R_N
C20  Q_CAP  2.2UF 6.3V 20% X6S  pkg C0402  page 88 : A = P3V3_AUX ; B = GND
PC269_P0_5  Q_CAP  22UF 4V 20% X6S  pkg C0805  page 269 : A = PVCCIN_CPU0 ; B = GND

(kicad_pcb
	(version 20260206)
	(generator "pcbnew")
	(generator_version "10.0")
	(general
		(thickness 1.6)
		(legacy_teardrops no)
	)
	(paper "A4")
	(title_block
		(title "03242023_DA0F0TMBIJ0_F0T_Motherboard_J_brd_V01_OCP.brd")
		(comment 1 "Grand Teton / footprints 4402-4404 of 6105")
	)
	(layers
		(0 "F.Cu" signal "TOP")
		(4 "In1.Cu" signal "GND")
		(6 "In2.Cu" signal "IN1")
		(8 "In3.Cu" signal "GND1")
		(10 "In4.Cu" signal "IN2")
		(12 "In5.Cu" signal "GND2")
		(14 "In6.Cu" signal "IN3")
		(16 "In7.Cu" signal "GND3")
		(18 "In8.Cu" signal "VCC")
		(20 "In9.Cu" signal "VCC1")
		(22 "In10.Cu" signal "GND4")
		(24 "In11.Cu" signal "IN4")
		(26 "In12.Cu" signal "GND5")
		(28 "In13.Cu" signal "IN5")
		(30 "In14.Cu" signal "GND6")
		(32 "In15.Cu" signal "IN6")
		(34 "In16.Cu" signal "GND7")
		(2 "B.Cu" signal "BOTTOM")
		(9 "F.Adhes" user "F.Adhesive")
		(11 "B.Adhes" user "B.Adhesive")
		(13 "F.Paste" user "Package Geometry/Pastemask Top")
		(15 "B.Paste" user "Package Geometry/Pastemask Bottom")
		(5 "F.SilkS" user "Ref Des/Silkscreen Top")
		(7 "B.SilkS" user "Ref Des/Silkscreen Bottom")
		(1 "F.Mask" user "Board Geometry/Soldermask Top")
		(3 "B.Mask" user "Board Geometry/Soldermask Bottom")
		(17 "Dwgs.User" user "User.Drawings")
		(19 "Cmts.User" user "User.Comments")
		(21 "Eco1.User" user "User.Eco1")
		(23 "Eco2.User" user "User.Eco2")
		(25 "Edge.Cuts" user "Board Geometry/Outline")
		(27 "Margin" user)
		(31 "F.CrtYd" user "Package Geometry/Place Bound Top")
		(29 "B.CrtYd" user "Package Geometry/Place Bound Bottom")
		(35 "F.Fab" user "Ref Des/Assembly Top")
		(33 "B.Fab" user "Ref Des/Assembly Bottom")
	)
	(footprint ""
		(layer "B.Cu")
		(at 380.977648 -328.65187 -90)
		(property "Reference" "PC269_P0_5"
			(at 0 0 90)
			(layer "B.SilkS")
			(hide yes)
			(effects
				(font
					(size 1.27 1.27)
				)
				(justify mirror)
			)
		)
		(property "Value" ""
			(at 0 0 90)
			(layer "B.Fab")
			(effects
				(font
					(size 1.27 1.27)
				)
				(justify mirror)
			)
		)
		(duplicate_pad_numbers_are_jumpers no)
		(fp_line
			(start -1.524 0.762)
			(end 1.524 0.762)
			(stroke
				(width 0.1524)
				(type default)
			)
			(layer "B.SilkS")
		)
		(fp_line
			(start 1.524 0.762)
			(end 1.524 -0.762)
			(stroke
				(width 0.1524)
				(type default)
			)
			(layer "B.SilkS")
		)
		(fp_line
			(start -1.524 -0.762)
			(end -1.524 0.762)
			(stroke
				(width 0.1524)
				(type default)
			)
			(layer "B.SilkS")
		)
		(fp_line
			(start 1.524 -0.762)
			(end -1.524 -0.762)
			(stroke
				(width 0.1524)
				(type default)
			)
			(layer "B.SilkS")
		)
		(fp_line
			(start -1.1049 0.724916)
			(end -1.1049 -0.724916)
			(stroke
				(width 0.1)
				(type default)
			)
			(layer "B.Fab")
		)
		(fp_line
			(start 1.1049 0.724916)
			(end -1.1049 0.724916)
			(stroke
				(width 0.1)
				(type default)
			)
			(layer "B.Fab")
		)
		(fp_line
			(start -1.1049 -0.724916)
			(end 1.1049 -0.724916)
			(stroke
				(width 0.1)
				(type default)
			)
			(layer "B.Fab")
		)
		(fp_line
			(start 1.1049 -0.724916)
			(end 1.1049 0.724916)
			(stroke
				(width 0.1)
				(type default)
			)
			(layer "B.Fab")
		)
		(pad "1" smd rect
			(at 0.889 0 270)
			(size 1.016 1.27)
			(layers "B.Cu" "B.Mask" "B.Paste")
			(net "PVCCIN_CPU0")
		)
		(pad "2" smd rect
			(at -0.889 0 270)
			(size 1.016 1.27)
			(layers "B.Cu" "B.Mask" "B.Paste")
			(net "GND")
		)
	)
	(footprint ""
		(layer "B.Cu")
		(at 256.09169 -319.48374 180)
		(property "Reference" "C20"
			(at 0 0 0)
			(layer "B.SilkS")
			(hide yes)
			(effects
				(font
					(size 1.27 1.27)
				)
				(justify mirror)
			)
		)
		(property "Value" ""
			(at 0 0 0)
			(layer "B.Fab")
			(effects
				(font
					(size 1.27 1.27)
				)
				(justify mirror)
			)
		)
		(duplicate_pad_numbers_are_jumpers no)
		(fp_line
			(start 0.7874 0.4064)
			(end 0.7874 -0.4064)
			(stroke
				(width 0.1524)
				(type default)
			)
			(layer "B.SilkS")
		)
		(fp_line
			(start 0.7874 -0.4064)
			(end -0.7874 -0.4064)
			(stroke
				(width 0.1524)
				(type default)
			)
			(layer "B.SilkS")
		)
		(fp_line
			(start -0.7874 0.4064)
			(end 0.7874 0.4064)
			(stroke
				(width 0.1524)
				(type default)
			)
			(layer "B.SilkS")
		)
		(fp_line
			(start -0.7874 -0.4064)
			(end -0.7874 0.4064)
			(stroke
				(width 0.1524)
				(type default)
			)
			(layer "B.SilkS")
		)
		(fp_line
			(start 0.67945 0.3048)
			(end 0.67945 -0.305054)
			(stroke
				(width 0.1)
				(type default)
			)
			(layer "B.Fab")
		)
		(fp_line
			(start 0.67945 -0.305054)
			(end 0.12065 -0.305054)
			(stroke
				(width 0.1)
				(type default)
			)
			(layer "B.Fab")
		)
		(fp_line
			(start 0.12065 0.3048)
			(end 0.67945 0.3048)
			(stroke
				(width 0.1)
				(type default)
			)
			(layer "B.Fab")
		)
		(fp_line
			(start 0.12065 0.2794)
			(end 0.12065 0.3048)
			(stroke
				(width 0.1)
				(type default)
			)
			(layer "B.Fab")
		)
		(fp_line
			(start 0.12065 -0.2794)
			(end -0.12065 -0.2794)
			(stroke
				(width 0.1)
				(type default)
			)
			(layer "B.Fab")
		)
		(fp_line
			(start 0.12065 -0.305054)
			(end 0.12065 -0.2794)
			(stroke
				(width 0.1)
				(type default)
			)
			(layer "B.Fab")
		)
		(fp_line
			(start -0.120396 0.3048)
			(end -0.120396 0.2794)
			(stroke
				(width 0.1)
				(type default)
			)
			(layer "B.Fab")
		)
		(fp_line
			(start -0.120396 0.2794)
			(end 0.12065 0.2794)
			(stroke
				(width 0.1)
				(type default)
			)
			(layer "B.Fab")
		)
		(fp_line
			(start -0.12065 -0.2794)
			(end -0.12065 -0.3048)
			(stroke
				(width 0.1)
				(type default)
			)
			(layer "B.Fab")
		)
		(fp_line
			(start -0.12065 -0.3048)
			(end -0.67945 -0.3048)
			(stroke
				(width 0.1)
				(type default)
			)
			(layer "B.Fab")
		)
		(fp_line
			(start -0.67945 0.3048)
			(end -0.120396 0.3048)
			(stroke
				(width 0.1)
				(type default)
			)
			(layer "B.Fab")
		)
		(fp_line
			(start -0.67945 -0.3048)
			(end -0.67945 0.3048)
			(stroke
				(width 0.1)
				(type default)
			)
			(layer "B.Fab")
		)
		(pad "1" smd circle
			(at 0.40005 0)
			(size 0 0)
			(layers "B.Cu" "B.Mask" "B.Paste")
			(net "P3V3_AUX")
		)
		(pad "2" smd circle
			(at -0.40005 0)
			(size 0 0)
			(layers "B.Cu" "B.Mask" "B.Paste")
			(net "GND")
		)
	)
	(footprint ""
		(layer "B.Cu")
		(at 346.497148 -32.58439 180)
		(property "Reference" "R2342"
			(at 0 0 0)
			(layer "B.SilkS")
			(hide yes)
			(effects
				(font
					(size 1.27 1.27)
				)
				(justify mirror)
			)
		)
		(property "Value" ""
			(at 0 0 0)
			(layer "B.Fab")
			(effects
				(font
					(size 1.27 1.27)
				)
				(justify mirror)
			)
		)
		(duplicate_pad_numbers_are_jumpers no)
		(fp_line
			(start 0.7874 0.4064)
			(end 0.7874 -0.4064)
			(stroke
				(width 0.1524)
				(type default)
			)
			(layer "B.SilkS")
		)
		(fp_line
			(start 0.7874 -0.4064)
			(end -0.7874 -0.4064)
			(stroke
				(width 0.1524)
				(type default)
			)
			(layer "B.SilkS")
		)
		(fp_line
			(start -0.7874 0.4064)
			(end 0.7874 0.4064)
			(stroke
				(width 0.1524)
				(type default)
			)
			(layer "B.SilkS")
		)
		(fp_line
			(start -0.7874 -0.4064)
			(end -0.7874 0.4064)
			(stroke
				(width 0.1524)
				(type default)
			)
			(layer "B.SilkS")
		)
		(fp_line
			(start 0.67945 0.3048)
			(end 0.67945 -0.305054)
			(stroke
				(width 0.1)
				(type default)
			)
			(layer "B.Fab")
		)
		(fp_line
			(start 0.67945 -0.305054)
			(end 0.12065 -0.305054)
			(stroke
				(width 0.1)
				(type default)
			)
			(layer "B.Fab")
		)
		(fp_line
			(start 0.12065 0.3048)
			(end 0.67945 0.3048)
			(stroke
				(width 0.1)
				(type default)
			)
			(layer "B.Fab")
		)
		(fp_line
			(start 0.12065 0.2794)
			(end 0.12065 0.3048)
			(stroke
				(width 0.1)
				(type default)
			)
			(layer "B.Fab")
		)
		(fp_line
			(start 0.12065 -0.2794)
			(end -0.12065 -0.2794)
			(stroke
				(width 0.1)
				(type default)
			)
			(layer "B.Fab")
		)
		(fp_line
			(start 0.12065 -0.305054)
			(end 0.12065 -0.2794)
			(stroke
				(width 0.1)
				(type default)
			)
			(layer "B.Fab")
		)
		(fp_line
			(start -0.120396 0.3048)
			(end -0.120396 0.2794)
			(stroke
				(width 0.1)
				(type default)
			)
			(layer "B.Fab")
		)
		(fp_line
			(start -0.120396 0.2794)
			(end 0.12065 0.2794)
			(stroke
				(width 0.1)
				(type default)
			)
			(layer "B.Fab")
		)
		(fp_line
			(start -0.12065 -0.2794)
			(end -0.12065 -0.3048)
			(stroke
				(width 0.1)
				(type default)
			)
			(layer "B.Fab")
		)
		(fp_line
			(start -0.12065 -0.3048)
			(end -0.67945 -0.3048)
			(stroke
				(width 0.1)
				(type default)
			)
			(layer "B.Fab")
		)
		(fp_line
			(start -0.67945 0.3048)
			(end -0.120396 0.3048)
			(stroke
				(width 0.1)
				(type default)
			)
			(layer "B.Fab")
		)
		(fp_line
			(start -0.67945 -0.3048)
			(end -0.67945 0.3048)
			(stroke
				(width 0.1)
				(type default)
			)
			(layer "B.Fab")
		)
		(pad "1" smd circle
			(at 0.40005 0)
			(size 0 0)
			(layers "B.Cu" "B.Mask" "B.Paste")
			(net "P3V3_AUX")
		)
		(pad "2" smd circle
			(at -0.40005 0)
			(size 0 0)
			(layers "B.Cu" "B.Mask" "B.Paste")
			(net "FM_DEBUG_PORT_PRSNT_R_N")
		)
	)
)
